(kicad_pcb
	(version 20260206)
	(generator "pcbnew")
	(generator_version "10.0")
	(general
		(thickness 1.6)
		(legacy_teardrops no)
	)
	(paper "A4")
	(title_block
		(title "Wiwynn_Tioga_Pass_MB.brd")
		(comment 1 "Tioga Pass / footprint 1695 of 4770 (J4E1), pads 1-122 of 122")
	)
	(layers
		(0 "F.Cu" signal "TOP")
		(4 "In1.Cu" signal "L2GND")
		(6 "In2.Cu" signal "L3")
		(8 "In3.Cu" signal "L4GND")
		(10 "In4.Cu" signal "L5")
		(12 "In5.Cu" signal "L6GND")
		(14 "In6.Cu" signal "L7VCC")
		(16 "In7.Cu" signal "L8VCC")
		(18 "In8.Cu" signal "L9GND")
		(20 "In9.Cu" signal "L10")
		(22 "In10.Cu" signal "L11GND")
		(24 "In11.Cu" signal "L12")
		(26 "In12.Cu" signal "L13GND")
		(2 "B.Cu" signal "BOTTOM")
		(9 "F.Adhes" user "F.Adhesive")
		(11 "B.Adhes" user "B.Adhesive")
		(13 "F.Paste" user "Package Geometry/Pastemask Top")
		(15 "B.Paste" user "Package Geometry/Pastemask Bottom")
		(5 "F.SilkS" user "Ref Des/Silkscreen Top")
		(7 "B.SilkS" user "Ref Des/Silkscreen Bottom")
		(1 "F.Mask" user "Board Geometry/Soldermask Top")
		(3 "B.Mask" user "Board Geometry/Soldermask Bottom")
		(17 "Dwgs.User" user "User.Drawings")
		(19 "Cmts.User" user "User.Comments")
		(21 "Eco1.User" user "User.Eco1")
		(23 "Eco2.User" user "User.Eco2")
		(25 "Edge.Cuts" user "Board Geometry/Outline")
		(27 "Margin" user)
		(31 "F.CrtYd" user "Package Geometry/Place Bound Top")
		(29 "B.CrtYd" user "Package Geometry/Place Bound Bottom")
		(35 "F.Fab" user "Ref Des/Assembly Top")
		(33 "B.Fab" user "Ref Des/Assembly Bottom")
	)
	(footprint ""
		(layer "F.Cu")
		(at 164.615114 -43.80103 90)
		(property "Reference" "J4E1"
			(at -3.59283 -5.018024 90)
			(unlocked yes)
			(layer "F.SilkS")
			(effects
				(font
					(size 0.7874 0.5842)
					(thickness 0.1524)
				)
			)
		)
		(property "Value" ""
			(at 0 0 90)
			(layer "F.Fab")
			(effects
				(font
					(size 1.27 1.27)
				)
			)
		)
		(duplicate_pad_numbers_are_jumpers no)
		(pad "" np_thru_hole circle
			(at -3.175 26.5557 90)
			(size 0.254 0.254)
			(drill 1.27)
			(layers "*.Cu" "*.Mask")
			(clearance 0.8255)
			(thermal_gap 0.8255)
		)
		(pad "" np_thru_hole circle
			(at -0.127 -2.4257 90)
			(size 0.254 0.254)
			(drill 1.27)
			(layers "*.Cu" "*.Mask")
			(clearance 0.8255)
			(thermal_gap 0.8255)
		)
		(pad "A1" smd circle
			(at 0 0 90)
			(size 0.635 0.635)
			(layers "F.Cu" "F.Mask" "F.Paste")
			(net "PVCCMCP_CPU1")
		)
		(pad "A2" smd circle
			(at 0 1.27 90)
			(size 0.635 0.635)
			(layers "F.Cu" "F.Mask" "F.Paste")
			(net "PVCCMCP_CPU1")
		)
		(pad "A3" smd circle
			(at 0 2.54 90)
			(size 0.635 0.635)
			(layers "F.Cu" "F.Mask" "F.Paste")
			(net "PVCCMCP_CPU1")
		)
		(pad "A4" smd circle
			(at 0 3.81 90)
			(size 0.635 0.635)
			(layers "F.Cu" "F.Mask" "F.Paste")
			(net "VSENSE_PVCCMCP_CPU1_SKT_VSEN")
		)
		(pad "A5" smd circle
			(at 0 5.08 90)
			(size 0.635 0.635)
			(layers "F.Cu" "F.Mask" "F.Paste")
			(net "PVCCMCP_CPU1")
		)
		(pad "A6" smd circle
			(at 0 6.35 90)
			(size 0.635 0.635)
			(layers "F.Cu" "F.Mask" "F.Paste")
			(net "PVCCMCP_CPU1")
		)
		(pad "A7" smd circle
			(at 0 7.62 90)
			(size 0.635 0.635)
			(layers "F.Cu" "F.Mask" "F.Paste")
			(net "PVCCMCP_CPU1")
		)
		(pad "A8" smd circle
			(at 0 8.89 90)
			(size 0.635 0.635)
			(layers "F.Cu" "F.Mask" "F.Paste")
			(net "PVCCMCP_CPU1")
		)
		(pad "A9" smd circle
			(at 0 10.16 90)
			(size 0.635 0.635)
			(layers "F.Cu" "F.Mask" "F.Paste")
			(net "PVCCMCP_CPU1")
		)
		(pad "A10" smd circle
			(at 0 11.43 90)
			(size 0.635 0.635)
			(layers "F.Cu" "F.Mask" "F.Paste")
			(net "PVCCMCP_CPU1")
		)
		(pad "A11" smd circle
			(at 0 12.7 90)
			(size 0.635 0.635)
			(layers "F.Cu" "F.Mask" "F.Paste")
			(net "PVCCMCP_CPU1")
		)
		(pad "A12" smd circle
			(at 0 13.97 90)
			(size 0.635 0.635)
			(layers "F.Cu" "F.Mask" "F.Paste")
			(net "PVCCMCP_CPU1")
		)
		(pad "A13" smd circle
			(at 0 15.24 90)
			(size 0.635 0.635)
			(layers "F.Cu" "F.Mask" "F.Paste")
			(net "PVCCMCP_CPU1")
		)
		(pad "A14" smd circle
			(at 0 16.51 90)
			(size 0.635 0.635)
			(layers "F.Cu" "F.Mask" "F.Paste")
			(net "PVCCMCP_CPU1")
		)
		(pad "A15" smd circle
			(at 0 17.78 90)
			(size 0.635 0.635)
			(layers "F.Cu" "F.Mask" "F.Paste")
			(net "PVCCMCP_CPU1")
		)
		(pad "A16" smd circle
			(at 0 19.05 90)
			(size 0.635 0.635)
			(layers "F.Cu" "F.Mask" "F.Paste")
			(net "PVCCMCP_CPU1")
		)
		(pad "A17" smd circle
			(at 0 20.32 90)
			(size 0.635 0.635)
			(layers "F.Cu" "F.Mask" "F.Paste")
			(net "PVCCMCP_CPU1")
		)
		(pad "A18" smd circle
			(at 0 21.59 90)
			(size 0.635 0.635)
			(layers "F.Cu" "F.Mask" "F.Paste")
			(net "PVCCMCP_CPU1")
		)
		(pad "A19" smd circle
			(at 0 22.86 90)
			(size 0.635 0.635)
			(layers "F.Cu" "F.Mask" "F.Paste")
			(net "GND")
		)
		(pad "A20" smd circle
			(at 0 24.13 90)
			(size 0.635 0.635)
			(layers "F.Cu" "F.Mask" "F.Paste")
			(net "GND")
		)
		(pad "B1" smd circle
			(at -1.27 0 90)
			(size 0.635 0.635)
			(layers "F.Cu" "F.Mask" "F.Paste")
			(net "PVCCMCP_CPU1")
		)
		(pad "B2" smd circle
			(at -1.27 1.27 90)
			(size 0.635 0.635)
			(layers "F.Cu" "F.Mask" "F.Paste")
			(net "PVCCMCP_CPU1")
		)
		(pad "B3" smd circle
			(at -1.27 2.54 90)
			(size 0.635 0.635)
			(layers "F.Cu" "F.Mask" "F.Paste")
			(net "PVCCMCP_CPU1")
		)
		(pad "B4" smd circle
			(at -1.27 3.81 90)
			(size 0.635 0.635)
			(layers "F.Cu" "F.Mask" "F.Paste")
			(net "VSENSE_PVCCMCP_CPU1_SKT_VRTN")
		)
		(pad "B5" smd circle
			(at -1.27 5.08 90)
			(size 0.635 0.635)
			(layers "F.Cu" "F.Mask" "F.Paste")
			(net "PVCCMCP_CPU1")
		)
		(pad "B6" smd circle
			(at -1.27 6.35 90)
			(size 0.635 0.635)
			(layers "F.Cu" "F.Mask" "F.Paste")
			(net "PVCCMCP_CPU1")
		)
		(pad "B7" smd circle
			(at -1.27 7.62 90)
			(size 0.635 0.635)
			(layers "F.Cu" "F.Mask" "F.Paste")
			(net "PVCCMCP_CPU1")
		)
		(pad "B8" smd circle
			(at -1.27 8.89 90)
			(size 0.635 0.635)
			(layers "F.Cu" "F.Mask" "F.Paste")
			(net "PVCCMCP_CPU1")
		)
		(pad "B9" smd circle
			(at -1.27 10.16 90)
			(size 0.635 0.635)
			(layers "F.Cu" "F.Mask" "F.Paste")
			(net "PVCCMCP_CPU1")
		)
		(pad "B10" smd circle
			(at -1.27 11.43 90)
			(size 0.635 0.635)
			(layers "F.Cu" "F.Mask" "F.Paste")
			(net "PVCCMCP_CPU1")
		)
		(pad "B11" smd circle
			(at -1.27 12.7 90)
			(size 0.635 0.635)
			(layers "F.Cu" "F.Mask" "F.Paste")
			(net "PVCCMCP_CPU1")
		)
		(pad "B12" smd circle
			(at -1.27 13.97 90)
			(size 0.635 0.635)
			(layers "F.Cu" "F.Mask" "F.Paste")
			(net "PVCCMCP_CPU1")
		)
		(pad "B13" smd circle
			(at -1.27 15.24 90)
			(size 0.635 0.635)
			(layers "F.Cu" "F.Mask" "F.Paste")
			(net "PVCCMCP_CPU1")
		)
		(pad "B14" smd circle
			(at -1.27 16.51 90)
			(size 0.635 0.635)
			(layers "F.Cu" "F.Mask" "F.Paste")
			(net "PVCCMCP_CPU1")
		)
		(pad "B15" smd circle
			(at -1.27 17.78 90)
			(size 0.635 0.635)
			(layers "F.Cu" "F.Mask" "F.Paste")
			(net "PVCCMCP_CPU1")
		)
		(pad "B16" smd circle
			(at -1.27 19.05 90)
			(size 0.635 0.635)
			(layers "F.Cu" "F.Mask" "F.Paste")
			(net "PVCCMCP_CPU1")
		)
		(pad "B17" smd circle
			(at -1.27 20.32 90)
			(size 0.635 0.635)
			(layers "F.Cu" "F.Mask" "F.Paste")
			(net "PVCCMCP_CPU1")
		)
		(pad "B18" smd circle
			(at -1.27 21.59 90)
			(size 0.635 0.635)
			(layers "F.Cu" "F.Mask" "F.Paste")
			(net "PVCCMCP_CPU1")
		)
		(pad "B19" smd circle
			(at -1.27 22.86 90)
			(size 0.635 0.635)
			(layers "F.Cu" "F.Mask" "F.Paste")
			(net "GND")
		)
		(pad "B20" smd circle
			(at -1.27 24.13 90)
			(size 0.635 0.635)
			(layers "F.Cu" "F.Mask" "F.Paste")
			(net "GND")
		)
		(pad "C1" smd circle
			(at -2.54 0 90)
			(size 0.635 0.635)
			(layers "F.Cu" "F.Mask" "F.Paste")
			(net "PVCCMCP_CPU1")
		)
		(pad "C2" smd circle
			(at -2.54 1.27 90)
			(size 0.635 0.635)
			(layers "F.Cu" "F.Mask" "F.Paste")
			(net "PVCCMCP_CPU1")
		)
		(pad "C3" smd circle
			(at -2.54 2.54 90)
			(size 0.635 0.635)
			(layers "F.Cu" "F.Mask" "F.Paste")
			(net "PVCCMCP_CPU1")
		)
		(pad "C4" smd circle
			(at -2.54 3.81 90)
			(size 0.635 0.635)
			(layers "F.Cu" "F.Mask" "F.Paste")
			(net "PVCCMCP_CPU1")
		)
		(pad "C5" smd circle
			(at -2.54 5.08 90)
			(size 0.635 0.635)
			(layers "F.Cu" "F.Mask" "F.Paste")
			(net "PVCCMCP_CPU1")
		)
		(pad "C6" smd circle
			(at -2.54 6.35 90)
			(size 0.635 0.635)
			(layers "F.Cu" "F.Mask" "F.Paste")
			(net "PVCCMCP_CPU1")
		)
		(pad "C7" smd circle
			(at -2.54 7.62 90)
			(size 0.635 0.635)
			(layers "F.Cu" "F.Mask" "F.Paste")
			(net "PVCCMCP_CPU1")
		)
		(pad "C8" smd circle
			(at -2.54 8.89 90)
			(size 0.635 0.635)
			(layers "F.Cu" "F.Mask" "F.Paste")
			(net "PVCCMCP_CPU1")
		)
		(pad "C9" smd circle
			(at -2.54 10.16 90)
			(size 0.635 0.635)
			(layers "F.Cu" "F.Mask" "F.Paste")
			(net "PVCCMCP_CPU1")
		)
		(pad "C10" smd circle
			(at -2.54 11.43 90)
			(size 0.635 0.635)
			(layers "F.Cu" "F.Mask" "F.Paste")
			(net "PVCCMCP_CPU1")
		)
		(pad "C11" smd circle
			(at -2.54 12.7 90)
			(size 0.635 0.635)
			(layers "F.Cu" "F.Mask" "F.Paste")
			(net "PVCCMCP_CPU1")
		)
		(pad "C12" smd circle
			(at -2.54 13.97 90)
			(size 0.635 0.635)
			(layers "F.Cu" "F.Mask" "F.Paste")
			(net "PVCCMCP_CPU1")
		)
		(pad "C13" smd circle
			(at -2.54 15.24 90)
			(size 0.635 0.635)
			(layers "F.Cu" "F.Mask" "F.Paste")
			(net "PVCCMCP_CPU1")
		)
		(pad "C14" smd circle
			(at -2.54 16.51 90)
			(size 0.635 0.635)
			(layers "F.Cu" "F.Mask" "F.Paste")
			(net "PVCCMCP_CPU1")
		)
		(pad "C15" smd circle
			(at -2.54 17.78 90)
			(size 0.635 0.635)
			(layers "F.Cu" "F.Mask" "F.Paste")
			(net "PVCCMCP_CPU1")
		)
		(pad "C16" smd circle
			(at -2.54 19.05 90)
			(size 0.635 0.635)
			(layers "F.Cu" "F.Mask" "F.Paste")
			(net "PVCCMCP_CPU1")
		)
		(pad "C17" smd circle
			(at -2.54 20.32 90)
			(size 0.635 0.635)
			(layers "F.Cu" "F.Mask" "F.Paste")
			(net "PVCCMCP_CPU1")
		)
		(pad "C18" smd circle
			(at -2.54 21.59 90)
			(size 0.635 0.635)
			(layers "F.Cu" "F.Mask" "F.Paste")
			(net "PVCCMCP_CPU1")
		)
		(pad "C19" smd circle
			(at -2.54 22.86 90)
			(size 0.635 0.635)
			(layers "F.Cu" "F.Mask" "F.Paste")
			(net "GND")
		)
		(pad "C20" smd circle
			(at -2.54 24.13 90)
			(size 0.635 0.635)
			(layers "F.Cu" "F.Mask" "F.Paste")
			(net "GND")
		)
		(pad "D1" smd circle
			(at -3.81 0 90)
			(size 0.635 0.635)
			(layers "F.Cu" "F.Mask" "F.Paste")
			(net "VSENSE_P1V8MCP_CPU1_SKT_VSEN")
		)
		(pad "D2" smd circle
			(at -3.81 1.27 90)
			(size 0.635 0.635)
			(layers "F.Cu" "F.Mask" "F.Paste")
			(net "VSENSE_P1V8MCP_CPU1_SKT_VRTN")
		)
		(pad "D3" smd circle
			(at -3.81 2.54 90)
			(size 0.635 0.635)
			(layers "F.Cu" "F.Mask" "F.Paste")
			(net "P1V8_MCP_CPU1")
		)
		(pad "D4" smd circle
			(at -3.81 3.81 90)
			(size 0.635 0.635)
			(layers "F.Cu" "F.Mask" "F.Paste")
			(net "GND")
		)
		(pad "D5" smd circle
			(at -3.81 5.08 90)
			(size 0.635 0.635)
			(layers "F.Cu" "F.Mask" "F.Paste")
			(net "GND")
		)
		(pad "D6" smd circle
			(at -3.81 6.35 90)
			(size 0.635 0.635)
			(layers "F.Cu" "F.Mask" "F.Paste")
			(net "GND")
		)
		(pad "D7" smd circle
			(at -3.81 7.62 90)
			(size 0.635 0.635)
			(layers "F.Cu" "F.Mask" "F.Paste")
			(net "GND")
		)
		(pad "D8" smd circle
			(at -3.81 8.89 90)
			(size 0.635 0.635)
			(layers "F.Cu" "F.Mask" "F.Paste")
			(net "GND")
		)
		(pad "D9" smd circle
			(at -3.81 10.16 90)
			(size 0.635 0.635)
			(layers "F.Cu" "F.Mask" "F.Paste")
			(net "GND")
		)
		(pad "D10" smd circle
			(at -3.81 11.43 90)
			(size 0.635 0.635)
			(layers "F.Cu" "F.Mask" "F.Paste")
			(net "GND")
		)
		(pad "D11" smd circle
			(at -3.81 12.7 90)
			(size 0.635 0.635)
			(layers "F.Cu" "F.Mask" "F.Paste")
			(net "GND")
		)
		(pad "D12" smd circle
			(at -3.81 13.97 90)
			(size 0.635 0.635)
			(layers "F.Cu" "F.Mask" "F.Paste")
			(net "GND")
		)
		(pad "D13" smd circle
			(at -3.81 15.24 90)
			(size 0.635 0.635)
			(layers "F.Cu" "F.Mask" "F.Paste")
			(net "GND")
		)
		(pad "D14" smd circle
			(at -3.81 16.51 90)
			(size 0.635 0.635)
			(layers "F.Cu" "F.Mask" "F.Paste")
			(net "GND")
		)
		(pad "D15" smd circle
			(at -3.81 17.78 90)
			(size 0.635 0.635)
			(layers "F.Cu" "F.Mask" "F.Paste")
			(net "GND")
		)
		(pad "D16" smd circle
			(at -3.81 19.05 90)
			(size 0.635 0.635)
			(layers "F.Cu" "F.Mask" "F.Paste")
			(net "GND")
		)
		(pad "D17" smd circle
			(at -3.81 20.32 90)
			(size 0.635 0.635)
			(layers "F.Cu" "F.Mask" "F.Paste")
			(net "GND")
		)
		(pad "D18" smd circle
			(at -3.81 21.59 90)
			(size 0.635 0.635)
			(layers "F.Cu" "F.Mask" "F.Paste")
			(net "GND")
		)
		(pad "D19" smd circle
			(at -3.81 22.86 90)
			(size 0.635 0.635)
			(layers "F.Cu" "F.Mask" "F.Paste")
			(net "GND")
		)
		(pad "D20" smd circle
			(at -3.81 24.13 90)
			(size 0.635 0.635)
			(layers "F.Cu" "F.Mask" "F.Paste")
			(net "GND")
		)
		(pad "E1" smd circle
			(at -5.08 0 90)
			(size 0.635 0.635)
			(layers "F.Cu" "F.Mask" "F.Paste")
			(net "P1V8_MCP_CPU1")
		)
		(pad "E2" smd circle
			(at -5.08 1.27 90)
			(size 0.635 0.635)
			(layers "F.Cu" "F.Mask" "F.Paste")
			(net "P1V8_MCP_CPU1")
		)
		(pad "E3" smd circle
			(at -5.08 2.54 90)
			(size 0.635 0.635)
			(layers "F.Cu" "F.Mask" "F.Paste")
			(net "P1V8_MCP_CPU1")
		)
		(pad "E4" smd circle
			(at -5.08 3.81 90)
			(size 0.635 0.635)
			(layers "F.Cu" "F.Mask" "F.Paste")
			(net "GND")
		)
		(pad "E5" smd circle
			(at -5.08 5.08 90)
			(size 0.635 0.635)
			(layers "F.Cu" "F.Mask" "F.Paste")
			(net "CLK_322M_156M_CPU1_OSC_VRM_DP")
		)
		(pad "E6" smd circle
			(at -5.08 6.35 90)
			(size 0.635 0.635)
			(layers "F.Cu" "F.Mask" "F.Paste")
			(net "GND")
		)
		(pad "E7" smd circle
			(at -5.08 7.62 90)
			(size 0.635 0.635)
			(layers "F.Cu" "F.Mask" "F.Paste")
			(net "GND")
		)
		(pad "E8" smd circle
			(at -5.08 8.89 90)
			(size 0.635 0.635)
			(layers "F.Cu" "F.Mask" "F.Paste")
			(net "GND")
		)
		(pad "E9" smd circle
			(at -5.08 10.16 90)
			(size 0.635 0.635)
			(layers "F.Cu" "F.Mask" "F.Paste")
			(net "GND")
		)
		(pad "E10" smd circle
			(at -5.08 11.43 90)
			(size 0.635 0.635)
			(layers "F.Cu" "F.Mask" "F.Paste")
			(net "GND")
		)
		(pad "E11" smd circle
			(at -5.08 12.7 90)
			(size 0.635 0.635)
			(layers "F.Cu" "F.Mask" "F.Paste")
			(net "GND")
		)
		(pad "E12" smd circle
			(at -5.08 13.97 90)
			(size 0.635 0.635)
			(layers "F.Cu" "F.Mask" "F.Paste")
			(net "GND")
		)
		(pad "E13" smd circle
			(at -5.08 15.24 90)
			(size 0.635 0.635)
			(layers "F.Cu" "F.Mask" "F.Paste")
			(net "GND")
		)
		(pad "E14" smd circle
			(at -5.08 16.51 90)
			(size 0.635 0.635)
			(layers "F.Cu" "F.Mask" "F.Paste")
			(net "GND")
		)
		(pad "E15" smd circle
			(at -5.08 17.78 90)
			(size 0.635 0.635)
			(layers "F.Cu" "F.Mask" "F.Paste")
			(net "GND")
		)
		(pad "E16" smd circle
			(at -5.08 19.05 90)
			(size 0.635 0.635)
			(layers "F.Cu" "F.Mask" "F.Paste")
			(net "GND")
		)
		(pad "E17" smd circle
			(at -5.08 20.32 90)
			(size 0.635 0.635)
			(layers "F.Cu" "F.Mask" "F.Paste")
			(net "GND")
		)
		(pad "E18" smd circle
			(at -5.08 21.59 90)
			(size 0.635 0.635)
			(layers "F.Cu" "F.Mask" "F.Paste")
			(net "GND")
		)
		(pad "E19" smd circle
			(at -5.08 22.86 90)
			(size 0.635 0.635)
			(layers "F.Cu" "F.Mask" "F.Paste")
			(net "GND")
		)
		(pad "E20" smd circle
			(at -5.08 24.13 90)
			(size 0.635 0.635)
			(layers "F.Cu" "F.Mask" "F.Paste")
			(net "GND")
		)
		(pad "F1" smd circle
			(at -6.35 0 90)
			(size 0.635 0.635)
			(layers "F.Cu" "F.Mask" "F.Paste")
			(net "P1V8_MCP_CPU1")
		)
		(pad "F2" smd circle
			(at -6.35 1.27 90)
			(size 0.635 0.635)
			(layers "F.Cu" "F.Mask" "F.Paste")
			(net "P1V8_MCP_CPU1")
		)
		(pad "F3" smd circle
			(at -6.35 2.54 90)
			(size 0.635 0.635)
			(layers "F.Cu" "F.Mask" "F.Paste")
			(net "P1V8_MCP_CPU1")
		)
		(pad "F4" smd circle
			(at -6.35 3.81 90)
			(size 0.635 0.635)
			(layers "F.Cu" "F.Mask" "F.Paste")
			(net "GND")
		)
		(pad "F5" smd circle
			(at -6.35 5.08 90)
			(size 0.635 0.635)
			(layers "F.Cu" "F.Mask" "F.Paste")
			(net "CLK_322M_156M_CPU1_OSC_VRM_DN")
		)
		(pad "F6" smd circle
			(at -6.35 6.35 90)
			(size 0.635 0.635)
			(layers "F.Cu" "F.Mask" "F.Paste")
			(net "GND")
		)
		(pad "F7" smd circle
			(at -6.35 7.62 90)
			(size 0.635 0.635)
			(layers "F.Cu" "F.Mask" "F.Paste")
			(net "GND")
		)
		(pad "F8" smd circle
			(at -6.35 8.89 90)
			(size 0.635 0.635)
			(layers "F.Cu" "F.Mask" "F.Paste")
			(net "GND")
		)
		(pad "F9" smd circle
			(at -6.35 10.16 90)
			(size 0.635 0.635)
			(layers "F.Cu" "F.Mask" "F.Paste")
			(net "GND")
		)
		(pad "F10" smd circle
			(at -6.35 11.43 90)
			(size 0.635 0.635)
			(layers "F.Cu" "F.Mask" "F.Paste")
			(net "GND")
		)
		(pad "F11" smd circle
			(at -6.35 12.7 90)
			(size 0.635 0.635)
			(layers "F.Cu" "F.Mask" "F.Paste")
			(net "GND")
		)
		(pad "F12" smd circle
			(at -6.35 13.97 90)
			(size 0.635 0.635)
			(layers "F.Cu" "F.Mask" "F.Paste")
			(net "GND")
		)
		(pad "F13" smd circle
			(at -6.35 15.24 90)
			(size 0.635 0.635)
			(layers "F.Cu" "F.Mask" "F.Paste")
			(net "GND")
		)
		(pad "F14" smd circle
			(at -6.35 16.51 90)
			(size 0.635 0.635)
			(layers "F.Cu" "F.Mask" "F.Paste")
			(net "GND")
		)
		(pad "F15" smd circle
			(at -6.35 17.78 90)
			(size 0.635 0.635)
			(layers "F.Cu" "F.Mask" "F.Paste")
			(net "GND")
		)
		(pad "F16" smd circle
			(at -6.35 19.05 90)
			(size 0.635 0.635)
			(layers "F.Cu" "F.Mask" "F.Paste")
			(net "GND")
		)
		(pad "F17" smd circle
			(at -6.35 20.32 90)
			(size 0.635 0.635)
			(layers "F.Cu" "F.Mask" "F.Paste")
			(net "GND")
		)
		(pad "F18" smd circle
			(at -6.35 21.59 90)
			(size 0.635 0.635)
			(layers "F.Cu" "F.Mask" "F.Paste")
			(net "GND")
		)
		(pad "F19" smd circle
			(at -6.35 22.86 90)
			(size 0.635 0.635)
			(layers "F.Cu" "F.Mask" "F.Paste")
			(net "GND")
		)
		(pad "F20" smd circle
			(at -6.35 24.13 90)
			(size 0.635 0.635)
			(layers "F.Cu" "F.Mask" "F.Paste")
			(net "GND")
		)
	)
)
